FILE_TYPE = CONNECTIVITY;
{Allegro Design Entry HDL 16.6-p007 (v16-6-112F) 10/10/2012}
"PAGE_NUMBER" = 206;
0"NC";
1"PVCCIO_CPU1\g";
2"P3V3_STBY\g";
3"P3V3_STBY\g";
4"GND\g";
5"GND\g";
6"GND\g";
7"GND\g";
8"GND\g";
9"GND\g";
10"PVCCIO_CPU1\g";
11"VR_FET_SW_P12V_STBY_PVCCIN_CPU1\g";
12"GND\g";
13"GND\g";
14"GND\g";
15"GND\g";
16"GND\g";
17"GND\g";
18"FM_PVCCIN_CPU1_PWR_IN_ALERT_N";
19"VR_PVCCIN_CPU1_PWM3"VOLTAGE"3.6";
20"ISENSE_PVSA_CPU1_IMON";
21"VR_PVSA_CPU1_BIREF1";
22"A_TSENSE_PVSA_CPU1";
23"VR_PVCCIN_CPU1_PWM4"VOLTAGE"3.6";
24"VR_PVCCIN_CPU1_PWM2"VOLTAGE"3.6";
25"VR_PVCCIN_CPU1_PWM1"VOLTAGE"3.6";
26"VR_PVSA_CPU1_PWM"VOLTAGE"3.6";
27"VR_PVCCIN_CPU1_AVINSEN"VOLTAGE"0.8";
28"FM_PVCCIN_PVCCSA_CPU1_EN_LVC1";
29"A_TSENSE_PVCCIN_CPU1"VOLTAGE"3.6";
30"VSENSE_PVSA_CPU1_N";
31"VSENSE_PVCCIN_CPU1_N";
32"VSENSE_PVCCIN_CPU1_AVSP";
33"ISENSE_PVCCIN_CPU1_PH5_IMON";
34"ISENSE_PVCCIN_CPU1_PH4_IMON";
35"VSENSE_PVSA_CPU1_P";
36"VR_PVCCIN_CPU1_AIREF3";
37"ISENSE_PVCCIN_CPU1_PH2_IMON";
38"VR_PVCCIN_CPU1_AIREF1";
39"VR_PVCCIN_CPU1_AIREF4";
40"VR_PVCCIN_CPU1_AIREF5";
41"ISENSE_PVCCIN_CPU1_PH1_IMON";
42"VSENSE_PVSA_CPU1_BVSP";
43"VR_PVCCIN_CPU1_VREN"VOLTAGE"3.3";
44"VR_PVCCIN_CPU1_XADDR1"VOLTAGE"3.3";
45"ISENSE_PVCCIN_CPU1_PH3_IMON";
46"SVID_CLK0_CPU1_R";
47"VR_PVCCIN_CPU1_AIREF2";
48"VSENSE_PVCCIN_CPU1_P";
49"SMB_VR_STBY_LVC3_SDA";
50"IRQ_PVCCIN_CPU1_VRHOT_LVC3_R_N";
51"SVID_VCLK_PVCCIN_CPU1";
52"VR_PVCCIN_CPU1_VDD"VOLTAGE"3.3";
53"VR_PVCCIN_CPU1_AVINSEN";
54"PU_VR_PVCCIN_CPU1_IMON";
55"SVID_DIO0_CPU1_R";
56"VR_PVCCIN_CPU1_XADDR2"VOLTAGE"3.3";
57"SMB_VR_STBY_LVC3_SCL";
58"PWRGD_PVSA_CPU1_R";
59"SVID_VALERT_VCCIN_CPU1";
60"VR_PVCCIN_CPU1_VD12";
61"SVID_VDIO_PVCCIN_CPU1";
62"IRQ_PVCCIN_CPU1_VRHOT_LVC3_N";
63"VR_PVCCIN_CPU1_PWM5";
64"PU_VR_PVCCIN_CPU1_FLT1_SMBALT_N_IMON";
65"VR_VRRDY_PVCCIN_CPU1";
66"SVID_ALERT0_CPU1_R_N";
67"PWRGD_PVSA_CPU1";
68"VR_PVCCIN_CPU1_VD12";
69"PWRGD_PVCCIN_CPU1";
%"PVCCIO_CPU1"
"1","(-1375,4150)","0","mstr_symbols","I1";
;
HDL_POWER"PVCCIO_CPU1"
BODY_TYPE"PLUMBING"
VOLTAGE"1.1V"
CDS_LIB"mstr_symbols";
"G\NAC"1;
%"P3V3_STBY"
"1","(-4350,4600)","0","mstr_symbols","I103";
;
HDL_POWER"P3V3_STBY"
BODY_TYPE"PLUMBING"
SIZE"1B"
CDS_LIB"mstr_symbols"
VOLTAGE"3.3V";
"G\NAC"2;
%"P3V3_STBY"
"1","(-3075,4575)","0","mstr_symbols","I104";
;
HDL_POWER"P3V3_STBY"
BODY_TYPE"PLUMBING"
SIZE"1B"
CDS_LIB"mstr_symbols"
VOLTAGE"3.3V";
"G\NAC"3;
%"RES"
"2","(-4500,925)","0","mstr_discrete","I111";
;
CDS_SEC"1"
VALUE"3.16K"
LOCATION"R9N7"
PART_NUMBER"G21796-043"
MATERIAL"CHIP"
WATTAGE"1/16W"
PACK_TYPE"0402"
TOLERANCE"1%"
SEC_TYPE"0402"
SEC"1"
CDS_LOCATION"R9N7"
ROOM"PVCCIN_CPU1_VR"
CDS_LIB"mstr_discrete";
"A"
$PN"1"56;
"B"
$PN"2"13;
%"RES"
"2","(-4825,925)","0","mstr_discrete","I112";
;
CDS_SEC"1"
TOLERANCE"1%"
VALUE"4.02K"
PART_NUMBER"G21796-082"
MATERIAL"CHIP"
PACK_TYPE"0402"
LOCATION"R9N8"
WATTAGE"1/16W"
SEC_TYPE"0402"
SEC"1"
CDS_LOCATION"R9N8"
ROOM"PVCCIN_CPU1_VR"
CDS_LIB"mstr_discrete";
"A"
$PN"1"44;
"B"
$PN"2"14;
%"RES"
"1","(-1200,3375)","0","mstr_discrete","I113";
;
CDS_SEC"1"
PART_NUMBER"G21796-250"
LOCATION"R1C30"
TOLERANCE"1.0%"
VALUE"22.1"
WATTAGE"1/16W"
MATERIAL"CHIP"
PACK_TYPE"0402"
SEC_TYPE"0402"
SEC"1"
ROOM"PVCCIN_CPU1_VR"
CDS_LOCATION"R1C30"
CDS_LIB"mstr_discrete";
"B"
$PN"2"69;
"A"
$PN"1"65;
%"CAP"
"1","(-1450,2150)","0","mstr_discrete","I114";
;
CDS_SEC"1"
VOLTAGE"50V"
TOLERANCE"10%"
VALUE"1000PF"
PACK_TYPE"0402LF"
MATERIAL"X7R"
PART_NUMBER"A36096-046"
LOCATION"C1C23"
ROOM"PVCCIN_CPU1_VR"
SEC"1"
SEC_TYPE"0402LF"
CDS_LOCATION"C1C23"
CDS_LIB"mstr_discrete";
"A"
$PN"1"65;
"B"
$PN"2"4;
%"GND"
"1","(-1450,1925)","0","mstr_symbols","I115";
;
HDL_POWER"GND"
BODY_TYPE"PLUMBING"
ROOM"PVCCIN_CPU1_VR"
CDS_LIB"mstr_symbols"
SIZE"1B"
VOLTAGE"0";
"A\NAC"4;
%"RES"
"1","(-2175,2725)","0","mstr_discrete","I116";
;
CDS_SEC"1"
LOCATION"R1D1"
MATERIAL"CHIP"
PART_NUMBER"G21796-074"
TOLERANCE"1%"
WATTAGE"1/16W"
VALUE"33.2"
PACK_TYPE"0402"
SEC_TYPE"0402"
SEC"1"
CDS_LIB"mstr_discrete"
CDS_LOCATION"R1D1";
"B"
$PN"2"67;
"A"
$PN"1"58;
%"RES"
"1","(-2375,3025)","0","mstr_discrete","I117";
;
CDS_SEC"1"
PART_NUMBER"G21796-074"
LOCATION"R9P3"
PACK_TYPE"0402"
VALUE"33.2"
MATERIAL"CHIP"
TOLERANCE"1%"
WATTAGE"1/16W"
CDS_LIB"mstr_discrete"
SEC_TYPE"0402"
SEC"1"
CDS_LOCATION"R9P3";
"B"
$PN"2"62;
"A"
$PN"1"50;
%"RES"
"1","(-5200,2275)","0","mstr_discrete","I119";
;
CDS_SEC"1"
LOCATION"R9N16"
PART_NUMBER"G21497-005"
PACK_TYPE"0402"
TOLERANCE"5%"
VALUE"0.0"
WATTAGE"1/16W"
MATERIAL"CHIP"
ROOM"PVCCIN_CPU0_VR"
CDS_LOCATION"R9N16"
SEC"1"
SEC_TYPE"0402"
CDS_LIB"mstr_discrete";
"B"
$PN"2"43;
"A"
$PN"1"28;
%"RES"
"2","(-4650,4400)","0","mstr_discrete","I120";
;
CDS_SEC"1"
MATERIAL"CHIP"
LOCATION"R9N14"
VALUE"1.00K"
TOLERANCE"1%"
PART_NUMBER"G21796-026"
PACK_TYPE"0402"
WATTAGE"1/16W"
BOM_COST"SM_CONTROLLER"
SEC_TYPE"0402"
SEC"1"
ROOM"BMC"
CDS_LOCATION"R9N14"
CDS_LIB"mstr_discrete";
"A"
$PN"1"10;
"B"
$PN"2"43;
%"PXE1610B"
"1","(-3825,2625)","0","mstr_controller","I130";
;
CDS_SEC"1"
MATERIAL"IC"
LOCATION"EU1C2"
PART_NUMBER"H79206-001"
CDS_LIB"mstr_controller"
CDS_LMAN_SYM_OUTLINE"-400,900,400,-900"
PACK_TYPE"QFN"
SEC_TYPE"QFN"
SEC"1"
CDS_LOCATION"EU1C2";
"VRHOT_N \B"
$PN"13"50;
"THPAD"
$PN"49"9;
"BPWM1"
$PN"1"26;
"APWM1"
$PN"7"25;
"APWM2"
$PN"6"24;
"APWM3"
$PN"5"19;
"APWM4"
$PN"4"23;
"APWM5"
$PN"3"63;
"APWM6"
$PN"2"0;
"SDA"
$PN"8"49;
"SCL"
$PN"9"57;
"VCLK"
$PN"17"51;
"VDIO"
$PN"18"61;
"RESET_N \B"
$PN"10"0;
"AISEN6"
$PN"34"0;
"AIREF6"
$PN"33"0;
"AISEN5"
$PN"32"33;
"AIREF5"
$PN"31"40;
"AISEN4"
$PN"30"34;
"AIREF4"
$PN"29"39;
"XADDR1"
$PN"44"44;
"AISEN3"
$PN"28"45;
"AIREF3"
$PN"27"36;
"XADDR2"
$PN"41"56;
"AISEN2"
$PN"26"37;
"AIREF2"
$PN"25"47;
"ATSEN"
$PN"43"29;
"AISEN1"
$PN"24"41;
"AIREF1"
$PN"23"38;
"VDD"
$PN"47"52;
"BTSEN"
$PN"42"22;
"BISEN1"
$PN"38"20;
"BIREF1"
$PN"37"21;
"PINALRT_N \B"
$PN"14"18;
"VALRT_N \B"
$PN"19"59;
"AVSEN"
$PN"21"32;
"AVREF"
$PN"22"31;
"BVSEN"
$PN"35"42;
"BVREF"
$PN"36"30;
"VINSEN"
$PN"45"27;
"IINSEN"
$PN"46"0;
"VD12"
$PN"48"60;
"AVRRDY"
$PN"11"65;
"AVREN"
$PN"12"43;
"MP0"
$PN"15"58;
"MP1"
$PN"16"0;
"MP2"
$PN"20"64;
"MP3"
$PN"39"54;
"MP4"
$PN"40"0;
%"SC22P50V2JN-4GP"
"1","(-6775,3350)","1","w_hdl","I137";
;
CDS_SEC"1"
$SEC"1"
CDS_LOCATION"CF7"
ATTRIBUTE"22PF"
RATED"50V"
TYPE"NPO"
TOLERANCE"5%"
PACK_SIZE"0402"
LOCATION"CF7"
VALUE"SC22P50V2JN-4GP"
GROUP"POWER_FAIR"
PACK_TYPE"SMD-BCG"
PART_NUMBER"78.22034.1FL"
CDS_LMAN_SYM_OUTLINE"-50,25,50,-25"
CDS_LIB"w_hdl";
"2"
$PN"2"41;
"1"
$PN"1"38;
%"SC22P50V2JN-4GP"
"1","(-6375,3350)","1","w_hdl","I138";
;
CDS_SEC"1"
CDS_LOCATION"CF8"
TYPE"NPO"
RATED"50V"
LOCATION"CF8"
TOLERANCE"5%"
ATTRIBUTE"22PF"
PACK_SIZE"0402"
VALUE"SC22P50V2JN-4GP"
GROUP"POWER_FAIR"
SEC_TYPE"SMD-BCG"
SEC"1"
PACK_TYPE"SMD-BCG"
CDS_LMAN_SYM_OUTLINE"-50,25,50,-25"
CDS_LIB"w_hdl"
PART_NUMBER"78.22034.1FL";
"2"
$PN"2"37;
"1"
$PN"1"47;
%"SC22P50V2JN-4GP"
"1","(-6000,3350)","1","w_hdl","I139";
;
CDS_SEC"1"
$SEC"1"
CDS_LOCATION"CF9"
PACK_SIZE"0402"
TYPE"NPO"
RATED"50V"
TOLERANCE"5%"
ATTRIBUTE"22PF"
LOCATION"CF9"
VALUE"SC22P50V2JN-4GP"
GROUP"POWER_FAIR"
CDS_LMAN_SYM_OUTLINE"-50,25,50,-25"
CDS_LIB"w_hdl"
PACK_TYPE"SMD-BCG"
PART_NUMBER"78.22034.1FL";
"2"
$PN"2"45;
"1"
$PN"1"36;
%"SC22P50V2JN-4GP"
"1","(-5550,3350)","1","w_hdl","I140";
;
CDS_SEC"1"
$SEC"1"
CDS_LOCATION"CF10"
RATED"50V"
ATTRIBUTE"22PF"
TYPE"NPO"
TOLERANCE"5%"
LOCATION"CF10"
PACK_SIZE"0402"
VALUE"SC22P50V2JN-4GP"
GROUP"POWER_FAIR"
CDS_LIB"w_hdl"
CDS_LMAN_SYM_OUTLINE"-50,25,50,-25"
PART_NUMBER"78.22034.1FL"
PACK_TYPE"SMD-BCG";
"2"
$PN"2"34;
"1"
$PN"1"39;
%"SC22P50V2JN-4GP"
"1","(-5100,3350)","1","w_hdl","I141";
;
CDS_SEC"1"
$SEC"1"
CDS_LOCATION"CF11"
TOLERANCE"5%"
ATTRIBUTE"22PF"
LOCATION"CF11"
GROUP"POWER_FAIR"
VALUE"SC22P50V2JN-4GP"
PACK_SIZE"0402"
RATED"50V"
TYPE"NPO"
PART_NUMBER"78.22034.1FL"
PACK_TYPE"SMD-BCG"
CDS_LMAN_SYM_OUTLINE"-50,25,50,-25"
CDS_LIB"w_hdl";
"2"
$PN"2"33;
"1"
$PN"1"40;
%"SC22P50V2JN-4GP"
"1","(-6525,1275)","1","w_hdl","I142";
;
CDS_SEC"1"
$SEC"1"
CDS_LOCATION"CF12"
LOCATION"CF12"
RATED"50V"
TOLERANCE"5%"
ATTRIBUTE"22PF"
GROUP"POWER_FAIR"
VALUE"SC22P50V2JN-4GP"
TYPE"NPO"
PACK_SIZE"0402"
PACK_TYPE"SMD-BCG"
PART_NUMBER"78.22034.1FL"
CDS_LMAN_SYM_OUTLINE"-50,25,50,-25"
CDS_LIB"w_hdl";
"2"
$PN"2"20;
"1"
$PN"1"21;
%"RES"
"1","(-6500,1425)","0","mstr_discrete","I149";
;
CDS_SEC"1"
CDS_LOCATION"RF12"
TOLERANCE"0.1%"
PACK_TYPE"0402"
LOCATION"RF12"
FAIR_SS"064.1101D.M001"
GROUP"POWER_FAIR"
PART_NUMBER"G85996-004"
VALUE"1.0K"
WATTAGE"1/16W"
MATERIAL"CHIP"
SEC_TYPE"0402"
SEC"1"
CDS_LIB"mstr_discrete"
ROOM"SB";
"B"
$PN"2"20;
"A"
$PN"1"21;
%"RES"
"1","(-6775,3500)","0","mstr_discrete","I150";
;
CDS_SEC"1"
CDS_LOCATION"RF7"
TOLERANCE"0.1%"
PACK_TYPE"0402"
LOCATION"RF7"
MATERIAL"CHIP"
GROUP"POWER_FAIR"
VALUE"1.0K"
PART_NUMBER"G85996-004"
FAIR_SS"064.9530D.M001"
WATTAGE"1/16W"
CDS_LIB"mstr_discrete"
ROOM"SB"
SEC"1"
SEC_TYPE"0402";
"B"
$PN"2"41;
"A"
$PN"1"38;
%"RES"
"1","(-6375,3500)","0","mstr_discrete","I151";
;
CDS_SEC"1"
CDS_LOCATION"RF8"
TOLERANCE"0.1%"
VALUE"1.0K"
LOCATION"RF8"
PART_NUMBER"G85996-004"
WATTAGE"1/16W"
MATERIAL"CHIP"
PACK_TYPE"0402"
FAIR_SS"064.9530D.M001"
GROUP"POWER_FAIR"
SEC_TYPE"0402"
SEC"1"
ROOM"SB"
CDS_LIB"mstr_discrete";
"B"
$PN"2"37;
"A"
$PN"1"47;
%"RES"
"1","(-6000,3500)","0","mstr_discrete","I152";
;
CDS_SEC"1"
CDS_LOCATION"RF9"
VALUE"1.0K"
LOCATION"RF9"
TOLERANCE"0.1%"
WATTAGE"1/16W"
PART_NUMBER"G85996-004"
PACK_TYPE"0402"
FAIR_SS"064.9530D.M001"
GROUP"POWER_FAIR"
MATERIAL"CHIP"
SEC"1"
SEC_TYPE"0402"
CDS_LIB"mstr_discrete"
ROOM"SB";
"B"
$PN"2"45;
"A"
$PN"1"36;
%"RES"
"1","(-5550,3500)","0","mstr_discrete","I153";
;
CDS_SEC"1"
CDS_LOCATION"RF10"
FAIR_SS"064.9530D.M001"
PART_NUMBER"G85996-004"
WATTAGE"1/16W"
VALUE"1.0K"
MATERIAL"CHIP"
TOLERANCE"0.1%"
PACK_TYPE"0402"
LOCATION"RF10"
GROUP"POWER_FAIR"
SEC"1"
SEC_TYPE"0402"
ROOM"SB"
CDS_LIB"mstr_discrete";
"B"
$PN"2"34;
"A"
$PN"1"39;
%"RES"
"1","(-5100,3500)","0","mstr_discrete","I154";
;
CDS_SEC"1"
CDS_LOCATION"RF11"
FAIR_SS"064.9530D.M001"
VALUE"1.0K"
LOCATION"RF11"
WATTAGE"1/16W"
PART_NUMBER"G85996-004"
GROUP"POWER_FAIR"
MATERIAL"CHIP"
PACK_TYPE"0402"
TOLERANCE"0.1%"
CDS_LIB"mstr_discrete"
ROOM"SB"
SEC_TYPE"0402"
SEC"1";
"B"
$PN"2"33;
"A"
$PN"1"40;
%"RES"
"2","(-2050,4150)","0","mstr_discrete","I155";
;
CDS_SEC"1"
WATTAGE"1/16W"
VALUE"1.00K"
PACK_TYPE"0402"
MATERIAL"CHIP"
TOLERANCE"1%"
LOCATION"R1D7"
PART_NUMBER"G21796-026"
CDS_LOCATION"R1D7"
SEC_TYPE"0402"
SEC"1"
ROOM"PVCCIN_CPU1_VR"
CDS_LIB"mstr_discrete";
"A"
$PN"1"3;
"B"
$PN"2"18;
%"CAP_A"
"1","(-6750,4200)","0","dev_discrete","I156";
;
MATERIAL"X7R"
TOLERANCE"10%"
VOLTAGE"16V"
VALUE"0.1UF"
LOCATION"C1C8"
PACK_TYPE"0402V"
PART_NUMBER"A36096-030"
CDS_LIB"dev_discrete"
BOM_COST"SM_THERM"
ROOM"CPU_FANS"
SEC_TYPE"0402V"
SEC"1"
CDS_SEC"1"
CDS_LOCATION"C1C8";
"B"
$PN"2"17;
"A"
$PN"1"53;
%"CAP_A"
"1","(-1575,1000)","0","dev_discrete","I29";
;
CDS_SEC"1"
PART_NUMBER"D97712-004"
VOLTAGE"6.3V"
MATERIAL"X6S"
TOLERANCE"10%"
PACK_TYPE"0402V"
LOCATION"C1C13"
VALUE"1.0UF"
ROOM"PVCCIN_CPU1_VR"
CDS_LOCATION"C1C13"
CDS_LIB"dev_discrete"
SEC"1"
SEC_TYPE"0402V";
"B"
$PN"2"5;
"A"
$PN"1"68;
%"GND"
"1","(-1575,675)","0","mstr_symbols","I30";
;
HDL_POWER"GND"
BODY_TYPE"PLUMBING"
SIZE"1B"
CDS_LIB"mstr_symbols"
VOLTAGE"0"
ROOM"PVCCIN_CPU1_VR";
"A\NAC"5;
%"CAP_A"
"1","(-1975,1000)","0","dev_discrete","I31";
;
PACK_TYPE"0402V"
MATERIAL"X7R"
PART_NUMBER"A36096-030"
VALUE"0.1UF"
LOCATION"C1C14"
VOLTAGE"16V"
TOLERANCE"10%"
ROOM"PVCCIN_CPU1_VR"
CDS_LOCATION"C1C14"
CDS_SEC"1"
SEC_TYPE"0402V"
SEC"1"
CDS_LIB"dev_discrete";
"B"
$PN"2"6;
"A"
$PN"1"68;
%"GND"
"1","(-1975,800)","0","mstr_symbols","I32";
;
HDL_POWER"GND"
BODY_TYPE"PLUMBING"
CDS_LIB"mstr_symbols"
VOLTAGE"0"
SIZE"1B"
ROOM"PVCCIN_CPU1_VR";
"A\NAC"6;
%"RES"
"2","(-2375,4125)","0","mstr_discrete","I33";
;
CDS_SEC"1"
CDS_LOCATION"R1D53"
LOCATION"R1D53"
PART_NUMBER"G21796-311"
VALUE"2.26K"
PACK_TYPE"0402"
WATTAGE"1/16W"
TOLERANCE"1.0%"
MATERIAL"EMPTY"
SEC_TYPE"0402"
SEC"1"
CDS_LIB"mstr_discrete"
ROOM"PVCCIN_CPU1_VR";
"A"
$PN"1"3;
"B"
$PN"2"64;
%"RES"
"2","(-2225,3750)","0","mstr_discrete","I34";
;
CDS_SEC"1"
TOLERANCE"1.0%"
VALUE"2.26K"
LOCATION"R1C18"
WATTAGE"1/16W"
MATERIAL"EMPTY"
PART_NUMBER"G21796-311"
PACK_TYPE"0402"
SEC_TYPE"0402"
SEC"1"
CDS_LOCATION"R1C18"
ROOM"PVCCIN_CPU1_VR"
CDS_LIB"mstr_discrete";
"A"
$PN"1"3;
"B"
$PN"2"54;
%"RES"
"2","(-2725,3925)","0","mstr_discrete","I35";
;
CDS_SEC"1"
PART_NUMBER"G21796-026"
MATERIAL"CHIP"
WATTAGE"1/16W"
PACK_TYPE"0402"
TOLERANCE"1%"
VALUE"1.00K"
LOCATION"R1C28"
CDS_LIB"mstr_discrete"
CDS_LOCATION"R1C28"
ROOM"PVCCIN_CPU1_VR"
SEC"1"
SEC_TYPE"0402";
"A"
$PN"1"3;
"B"
$PN"2"65;
%"RES"
"2","(-2875,3925)","2","mstr_discrete","I36";
;
CDS_SEC"1"
MATERIAL"CHIP"
TOLERANCE"1%"
VALUE"1.00K"
LOCATION"R1D8"
WATTAGE"1/16W"
PART_NUMBER"G21796-026"
PACK_TYPE"0402"
SEC_TYPE"0402"
SEC"1"
ROOM"PVCCIN_CPU1_VR"
CDS_LIB"mstr_discrete"
CDS_LOCATION"R1D8";
"A"
$PN"1"3;
"B"
$PN"2"58;
%"RES"
"1","(-2125,2925)","0","mstr_discrete","I37";
;
CDS_SEC"1"
LOCATION"R1D3"
WATTAGE"1/16W"
MATERIAL"CHIP"
VALUE"0.0"
TOLERANCE"5%"
PACK_TYPE"0402"
PART_NUMBER"G21497-005"
SEC"1"
SEC_TYPE"0402"
ROOM"PVCCIN_CPU1_VR"
CDS_LOCATION"R1D3"
CDS_LIB"mstr_discrete";
"B"
$PN"2"66;
"A"
$PN"1"59;
%"RES"
"1","(-2500,2775)","0","mstr_discrete","I38";
;
CDS_SEC"1"
MATERIAL"CHIP"
LOCATION"R1D2"
PACK_TYPE"0402"
TOLERANCE"5%"
WATTAGE"1/16W"
VALUE"0.0"
PART_NUMBER"G21497-005"
ROOM"PVCCIN_CPU1_VR"
CDS_LOCATION"R1D2"
SEC"1"
SEC_TYPE"0402"
CDS_LIB"mstr_discrete";
"B"
$PN"2"55;
"A"
$PN"1"61;
%"RES"
"2","(-1375,3750)","0","mstr_discrete","I4";
;
CDS_SEC"1"
WATTAGE"1/16W"
TOLERANCE"1%"
LOCATION"R9P1"
PACK_TYPE"0402"
PART_NUMBER"G21796-017"
MATERIAL"CHIP"
VALUE"100.0"
SEC_TYPE"0402"
SEC"1"
CDS_LOCATION"R9P1"
ROOM"PVCCIN_CPU1_VR"
CDS_LIB"mstr_discrete";
"A"
$PN"1"1;
"B"
$PN"2"55;
%"GND"
"1","(-3650,3725)","0","mstr_symbols","I40";
;
HDL_POWER"GND"
BODY_TYPE"PLUMBING"
SIZE"1B"
VOLTAGE"0"
CDS_LIB"mstr_symbols"
ROOM"PVCCIN_CPU1_VR";
"A\NAC"7;
%"CAP_A"
"1","(-3650,3925)","0","dev_discrete","I41";
;
LOCATION"C1C7"
PART_NUMBER"D97712-004"
VALUE"1.0UF"
TOLERANCE"10%"
PACK_TYPE"0402V"
VOLTAGE"6.3V"
MATERIAL"X6S"
CDS_SEC"1"
$SEC"1"
ROOM"PVCCIN_CPU1_VR"
CDS_LOCATION"C1C7"
CDS_LIB"dev_discrete";
"B"
$PN"2"7;
"A"
$PN"1"52;
%"CAP_A"
"1","(-4050,3925)","0","dev_discrete","I42";
;
PACK_TYPE"0402V"
PART_NUMBER"A36096-030"
TOLERANCE"10%"
VALUE"0.1UF"
LOCATION"C1C9"
MATERIAL"X7R"
VOLTAGE"16V"
SEC_TYPE"0402V"
SEC"1"
ROOM"PVCCIN_CPU1_VR"
CDS_SEC"1"
CDS_LOCATION"C1C9"
CDS_LIB"dev_discrete";
"B"
$PN"2"8;
"A"
$PN"1"52;
%"GND"
"1","(-4050,3725)","0","mstr_symbols","I43";
;
HDL_POWER"GND"
BODY_TYPE"PLUMBING"
VOLTAGE"0"
CDS_LIB"mstr_symbols"
SIZE"1B"
ROOM"PVCCIN_CPU1_VR";
"A\NAC"8;
%"GND"
"1","(-3175,1550)","0","mstr_symbols","I44";
;
HDL_POWER"GND"
BODY_TYPE"PLUMBING"
CDS_LIB"mstr_symbols"
VOLTAGE"0"
SIZE"1B"
ROOM"PVCCIN_CPU1_VR";
"A\NAC"9;
%"RES"
"2","(-4350,4275)","0","mstr_discrete","I46";
;
CDS_SEC"1"
PART_NUMBER"G21497-005"
LOCATION"R1C14"
VALUE"0.0"
TOLERANCE"5%"
PACK_TYPE"0402"
MATERIAL"CHIP"
WATTAGE"1/16W"
ROOM"PVCCIN_CPU1_VR"
CDS_LOCATION"R1C14"
SEC"1"
SEC_TYPE"0402"
CDS_LIB"mstr_discrete";
"A"
$PN"1"2;
"B"
$PN"2"52;
%"PVCCIO_CPU1"
"1","(-5225,4875)","0","mstr_symbols","I47";
;
HDL_POWER"PVCCIO_CPU1"
BODY_TYPE"PLUMBING"
CDS_LIB"mstr_symbols"
VOLTAGE"1.1V";
"G\NAC"10;
%"VCC_CORE"
"1","(-6150,4875)","0","mstr_symbols","I48";
;
HDL_POWER"VR_FET_SW_P12V_STBY_PVCCIN_CPU1"
VOLTAGE"12"
CDS_LIB"mstr_symbols";
"A"
VOLTAGE"+3.3V"11;
%"RES"
"2","(-6150,4575)","0","mstr_discrete","I49";
;
CDS_SEC"1"
PACK_TYPE"0402"
LOCATION"R1C13"
MATERIAL"CHIP"
WATTAGE"1/16W"
TOLERANCE"1%"
VALUE"100.0K"
PART_NUMBER"G21796-160"
SEC_TYPE"0402"
SEC"1"
CDS_LOCATION"R1C13"
ROOM"PVCCIN_CPU1_VR"
CDS_LIB"mstr_discrete";
"A"
$PN"1"11;
"B"
$PN"2"53;
%"RES"
"2","(-5650,4450)","0","mstr_discrete","I53";
;
CDS_SEC"1"
PART_NUMBER"G21796-047"
LOCATION"R9P2"
MATERIAL"CHIP"
WATTAGE"1/16W"
TOLERANCE"1%"
VALUE"49.9"
PACK_TYPE"0402"
SEC"1"
SEC_TYPE"0402"
ROOM"PVCCIN_CPU1_VR"
CDS_LOCATION"R9P2"
CDS_LIB"mstr_discrete";
"A"
$PN"1"10;
"B"
$PN"2"46;
%"RES"
"1","(-5375,3900)","0","mstr_discrete","I54";
;
TOLERANCE"1%"
LOCATION"R1D9"
PART_NUMBER"G21796-009"
VALUE"150.0"
MATERIAL"CHIP"
WATTAGE"1/16W"
PACK_TYPE"0402"
ROOM"PVCCIN_CPU1_VR"
$SEC"1"
CDS_SEC"1"
CDS_LOCATION"R1D9"
CDS_LIB"mstr_discrete";
"B"
$PN"2"51;
"A"
$PN"1"46;
%"RES"
"2","(-6150,4225)","0","mstr_discrete","I56";
;
CDS_SEC"1"
MATERIAL"CHIP"
PART_NUMBER"G21796-003"
PACK_TYPE"0402"
TOLERANCE"1%"
VALUE"1.5K"
LOCATION"R1C16"
WATTAGE"1/16W"
SEC"1"
CDS_LOCATION"R1C16"
ROOM"PVCCIN_CPU1_VR"
SEC_TYPE"0402"
CDS_LIB"mstr_discrete";
"A"
$PN"1"53;
"B"
$PN"2"12;
%"GND"
"1","(-6150,3975)","0","mstr_symbols","I57";
;
HDL_POWER"GND"
BODY_TYPE"PLUMBING"
ROOM"PVCCIN_CPU1_VR"
SIZE"1B"
CDS_LIB"mstr_symbols"
VOLTAGE"0";
"A\NAC"12;
%"RES"
"2","(-3150,4000)","2","mstr_discrete","I6";
;
CDS_SEC"1"
PACK_TYPE"0402"
PART_NUMBER"G21796-026"
MATERIAL"CHIP"
WATTAGE"1/16W"
VALUE"1.00K"
LOCATION"R1D6"
TOLERANCE"1%"
CDS_LIB"mstr_discrete"
SEC_TYPE"0402"
SEC"1"
CDS_LOCATION"R1D6"
ROOM"PVCCIN_CPU1_VR";
"A"
$PN"1"3;
"B"
$PN"2"50;
%"GND"
"1","(-4500,575)","0","mstr_symbols","I65";
;
HDL_POWER"GND"
BODY_TYPE"PLUMBING"
VOLTAGE"0"
CDS_LIB"mstr_symbols"
SIZE"1B"
ROOM"PVCCIN_CPU1_VR";
"A\NAC"13;
%"GND"
"1","(-4825,525)","0","mstr_symbols","I67";
;
HDL_POWER"GND"
BODY_TYPE"PLUMBING"
VOLTAGE"0"
CDS_LIB"mstr_symbols"
SIZE"1B"
ROOM"PVCCIN_CPU1_VR";
"A\NAC"14;
%"CAP"
"1","(-5650,2075)","0","mstr_discrete","I68";
;
CDS_SEC"1"
LOCATION"C1C16"
VOLTAGE"50V"
MATERIAL"X7R"
VALUE"220PF"
TOLERANCE"10%"
PACK_TYPE"0402LF"
PART_NUMBER"A36096-050"
SEC"1"
NO_XNET_CONNECTION"1"
SEC_TYPE"0402LF"
CDS_LIB"mstr_discrete"
CDS_LOCATION"C1C16"
ROOM"PVCCIN_CPU1_VR";
"A"
$PN"1"42;
"B"
$PN"2"30;
%"CAP"
"1","(-5925,1275)","0","mstr_discrete","I69";
;
CDS_SEC"1"
LOCATION"C1C10"
VOLTAGE"50V"
MATERIAL"X7R"
TOLERANCE"10%"
VALUE"220PF"
PACK_TYPE"0402LF"
PART_NUMBER"A36096-050"
SEC"1"
SEC_TYPE"0402LF"
CDS_LOCATION"C1C10"
ROOM"PVCCIN_CPU1_VR"
CDS_LIB"mstr_discrete";
"A"
$PN"1"29;
"B"
$PN"2"15;
%"GND"
"1","(-5925,475)","0","mstr_symbols","I70";
;
HDL_POWER"GND"
BODY_TYPE"PLUMBING"
SIZE"1B"
CDS_LIB"mstr_symbols"
VOLTAGE"0"
ROOM"PVCCIN_CPU1_VR";
"A\NAC"15;
%"CAP"
"1","(-6150,650)","2","mstr_discrete","I71";
;
CDS_SEC"1"
VOLTAGE"50V"
VALUE"220PF"
TOLERANCE"10%"
PART_NUMBER"A36096-050"
MATERIAL"X7R"
LOCATION"C1C11"
PACK_TYPE"0402LF"
CDS_LIB"mstr_discrete"
SEC_TYPE"0402LF"
SEC"1"
CDS_LOCATION"C1C11"
ROOM"PVCCIN_CPU1_VR";
"A"
$PN"1"22;
"B"
$PN"2"16;
%"GND"
"1","(-6150,475)","0","mstr_symbols","I72";
;
HDL_POWER"GND"
BODY_TYPE"PLUMBING"
SIZE"1B"
VOLTAGE"0"
CDS_LIB"mstr_symbols"
ROOM"PVCCIN_CPU1_VR";
"A\NAC"16;
%"GND"
"1","(-6750,4025)","0","mstr_symbols","I74";
;
VOLTAGE"0"
CDS_LIB"mstr_symbols"
SIZE"1B"
ROOM"PVCCIN_CPU1_VR"
BODY_TYPE"PLUMBING"
HDL_POWER"GND";
"A\NAC"17;
%"RES"
"1","(-6350,2075)","0","mstr_discrete","I77";
;
CDS_SEC"1"
MATERIAL"CHIP"
LOCATION"R1C21"
PART_NUMBER"G21796-066"
VALUE"10.0"
WATTAGE"1/16W"
NO_XNET_CONNECTION"1"
PACK_TYPE"0402"
TOLERANCE"1%"
CDS_LIB"mstr_discrete"
SEC_TYPE"0402"
SEC"1"
CDS_LOCATION"R1C21"
ROOM"PVCCIN_CPU1_VR";
"B"
$PN"2"42;
"A"
$PN"1"35;
%"CAP"
"1","(-6550,2375)","0","mstr_discrete","I78";
;
CDS_SEC"1"
PART_NUMBER"A36096-050"
TOLERANCE"10%"
PACK_TYPE"0402LF"
NO_XNET_CONNECTION"1"
VALUE"220PF"
LOCATION"C1D1"
VOLTAGE"50V"
MATERIAL"X7R"
SEC_TYPE"0402LF"
SEC"1"
ROOM"PVCCIN_CPU1_VR"
CDS_LOCATION"C1D1"
CDS_LIB"mstr_discrete";
"A"
$PN"1"32;
"B"
$PN"2"31;
%"RES"
"1","(-6775,2575)","0","mstr_discrete","I79";
;
CDS_SEC"1"
PART_NUMBER"G21796-066"
WATTAGE"1/16W"
PACK_TYPE"0402"
TOLERANCE"1%"
NO_XNET_CONNECTION"1"
VALUE"10.0"
MATERIAL"CHIP"
LOCATION"R1D4"
SEC_TYPE"0402"
CDS_LIB"mstr_discrete"
ROOM"PVCCIN_CPU1_VR"
CDS_LOCATION"R1D4"
SEC"1";
"B"
$PN"2"32;
"A"
$PN"1"48;
END.
